# T6G (Grand Teton) — schematic netlist excerpt (pin names and nets, part order shuffled) for the footprints in the layout excerpt that follows; sources: Cadence DE-HDL packaged netlist, KiCad conversion of 04192023_DAF0TMB3IC0_F0TG_MB_C_brd_V02_OCP.brd

C604  Q_CAP  0.001UF 50V 10% X7R  pkg C0402  page 172 : A = HDT_HDR_TCK ; B = GND
R6206  Q_RES  10K 1% CHIP  pkg 0402LF  page 176 : A = P3V3_AUX ; B = PU_CPU0_USB_HUB_RESERVED2

(kicad_pcb
	(version 20260206)
	(generator "pcbnew")
	(generator_version "10.0")
	(general
		(thickness 1.6)
		(legacy_teardrops no)
	)
	(paper "A4")
	(title_block
		(title "04192023_DAF0TMB3IC0_F0TG_MB_C_brd_V02_OCP.brd")
		(comment 1 "Grand Teton / footprints 2661-2662 of 8354")
	)
	(layers
		(0 "F.Cu" signal "TOP")
		(4 "In1.Cu" signal "GND")
		(6 "In2.Cu" signal "IN1")
		(8 "In3.Cu" signal "GND1")
		(10 "In4.Cu" signal "IN2")
		(12 "In5.Cu" signal "GND2")
		(14 "In6.Cu" signal "IN3")
		(16 "In7.Cu" signal "GND3")
		(18 "In8.Cu" signal "VCC")
		(20 "In9.Cu" signal "VCC1")
		(22 "In10.Cu" signal "GND4")
		(24 "In11.Cu" signal "IN4")
		(26 "In12.Cu" signal "GND5")
		(28 "In13.Cu" signal "IN5")
		(30 "In14.Cu" signal "GND6")
		(32 "In15.Cu" signal "IN6")
		(34 "In16.Cu" signal "GND7")
		(2 "B.Cu" signal "BOTTOM")
		(9 "F.Adhes" user "F.Adhesive")
		(11 "B.Adhes" user "B.Adhesive")
		(13 "F.Paste" user "Package Geometry/Pastemask Top")
		(15 "B.Paste" user "Package Geometry/Pastemask Bottom")
		(5 "F.SilkS" user "Ref Des/Silkscreen Top")
		(7 "B.SilkS" user "Ref Des/Silkscreen Bottom")
		(1 "F.Mask" user "Board Geometry/Soldermask Top")
		(3 "B.Mask" user "Board Geometry/Soldermask Bottom")
		(17 "Dwgs.User" user "User.Drawings")
		(19 "Cmts.User" user "User.Comments")
		(21 "Eco1.User" user "User.Eco1")
		(23 "Eco2.User" user "User.Eco2")
		(25 "Edge.Cuts" user "Board Geometry/Outline")
		(27 "Margin" user)
		(31 "F.CrtYd" user "Package Geometry/Place Bound Top")
		(29 "B.CrtYd" user "Package Geometry/Place Bound Bottom")
		(35 "F.Fab" user "Ref Des/Assembly Top")
		(33 "B.Fab" user "Ref Des/Assembly Bottom")
	)
	(footprint ""
		(layer "F.Cu")
		(at 387.431026 -51.1175)
		(property "Reference" "C604"
			(at 0 0 0)
			(layer "F.SilkS")
			(hide yes)
			(effects
				(font
					(size 1.27 1.27)
				)
			)
		)
		(property "Value" ""
			(at 0 0 0)
			(layer "F.Fab")
			(effects
				(font
					(size 1.27 1.27)
				)
			)
		)
		(duplicate_pad_numbers_are_jumpers no)
		(fp_line
			(start -0.7874 -0.4064)
			(end 0.7874 -0.4064)
			(stroke
				(width 0.1524)
				(type default)
			)
			(layer "F.SilkS")
		)
		(fp_line
			(start -0.7874 0.4064)
			(end -0.7874 -0.4064)
			(stroke
				(width 0.1524)
				(type default)
			)
			(layer "F.SilkS")
		)
		(fp_line
			(start 0.7874 -0.4064)
			(end 0.7874 0.4064)
			(stroke
				(width 0.1524)
				(type default)
			)
			(layer "F.SilkS")
		)
		(fp_line
			(start 0.7874 0.4064)
			(end -0.7874 0.4064)
			(stroke
				(width 0.1524)
				(type default)
			)
			(layer "F.SilkS")
		)
		(fp_line
			(start -0.67945 -0.305054)
			(end -0.12065 -0.305054)
			(stroke
				(width 0.1)
				(type default)
			)
			(layer "F.Fab")
		)
		(fp_line
			(start -0.67945 0.3048)
			(end -0.67945 -0.305054)
			(stroke
				(width 0.1)
				(type default)
			)
			(layer "F.Fab")
		)
		(fp_line
			(start -0.12065 -0.305054)
			(end -0.12065 -0.2794)
			(stroke
				(width 0.1)
				(type default)
			)
			(layer "F.Fab")
		)
		(fp_line
			(start -0.12065 -0.2794)
			(end 0.12065 -0.2794)
			(stroke
				(width 0.1)
				(type default)
			)
			(layer "F.Fab")
		)
		(fp_line
			(start -0.12065 0.2794)
			(end -0.12065 0.3048)
			(stroke
				(width 0.1)
				(type default)
			)
			(layer "F.Fab")
		)
		(fp_line
			(start -0.12065 0.3048)
			(end -0.67945 0.3048)
			(stroke
				(width 0.1)
				(type default)
			)
			(layer "F.Fab")
		)
		(fp_line
			(start 0.120396 0.2794)
			(end -0.12065 0.2794)
			(stroke
				(width 0.1)
				(type default)
			)
			(layer "F.Fab")
		)
		(fp_line
			(start 0.120396 0.3048)
			(end 0.120396 0.2794)
			(stroke
				(width 0.1)
				(type default)
			)
			(layer "F.Fab")
		)
		(fp_line
			(start 0.12065 -0.3048)
			(end 0.67945 -0.3048)
			(stroke
				(width 0.1)
				(type default)
			)
			(layer "F.Fab")
		)
		(fp_line
			(start 0.12065 -0.2794)
			(end 0.12065 -0.3048)
			(stroke
				(width 0.1)
				(type default)
			)
			(layer "F.Fab")
		)
		(fp_line
			(start 0.67945 -0.3048)
			(end 0.67945 0.3048)
			(stroke
				(width 0.1)
				(type default)
			)
			(layer "F.Fab")
		)
		(fp_line
			(start 0.67945 0.3048)
			(end 0.120396 0.3048)
			(stroke
				(width 0.1)
				(type default)
			)
			(layer "F.Fab")
		)
		(pad "1" smd circle
			(at -0.40005 0)
			(size 0 0)
			(layers "F.Cu" "F.Mask" "F.Paste")
			(net "HDT_HDR_TCK")
		)
		(pad "2" smd circle
			(at 0.40005 0)
			(size 0 0)
			(layers "F.Cu" "F.Mask" "F.Paste")
			(net "GND")
		)
	)
	(footprint ""
		(layer "F.Cu")
		(at 137.971784 -48.325024 180)
		(property "Reference" "R6206"
			(at 0 0 180)
			(layer "F.SilkS")
			(hide yes)
			(effects
				(font
					(size 1.27 1.27)
				)
			)
		)
		(property "Value" ""
			(at 0 0 180)
			(layer "F.Fab")
			(effects
				(font
					(size 1.27 1.27)
				)
			)
		)
		(duplicate_pad_numbers_are_jumpers no)
		(fp_line
			(start 0.7874 0.4064)
			(end -0.7874 0.4064)
			(stroke
				(width 0.1524)
				(type default)
			)
			(layer "F.SilkS")
		)
		(fp_line
			(start 0.7874 -0.4064)
			(end 0.7874 0.4064)
			(stroke
				(width 0.1524)
				(type default)
			)
			(layer "F.SilkS")
		)
		(fp_line
			(start -0.7874 0.4064)
			(end -0.7874 -0.4064)
			(stroke
				(width 0.1524)
				(type default)
			)
			(layer "F.SilkS")
		)
		(fp_line
			(start -0.7874 -0.4064)
			(end 0.7874 -0.4064)
			(stroke
				(width 0.1524)
				(type default)
			)
			(layer "F.SilkS")
		)
		(fp_line
			(start 0.67945 0.3048)
			(end 0.120396 0.3048)
			(stroke
				(width 0.1)
				(type default)
			)
			(layer "F.Fab")
		)
		(fp_line
			(start 0.67945 -0.3048)
			(end 0.67945 0.3048)
			(stroke
				(width 0.1)
				(type default)
			)
			(layer "F.Fab")
		)
		(fp_line
			(start 0.12065 -0.2794)
			(end 0.12065 -0.3048)
			(stroke
				(width 0.1)
				(type default)
			)
			(layer "F.Fab")
		)
		(fp_line
			(start 0.12065 -0.3048)
			(end 0.67945 -0.3048)
			(stroke
				(width 0.1)
				(type default)
			)
			(layer "F.Fab")
		)
		(fp_line
			(start 0.120396 0.3048)
			(end 0.120396 0.2794)
			(stroke
				(width 0.1)
				(type default)
			)
			(layer "F.Fab")
		)
		(fp_line
			(start 0.120396 0.2794)
			(end -0.12065 0.2794)
			(stroke
				(width 0.1)
				(type default)
			)
			(layer "F.Fab")
		)
		(fp_line
			(start -0.12065 0.3048)
			(end -0.67945 0.3048)
			(stroke
				(width 0.1)
				(type default)
			)
			(layer "F.Fab")
		)
		(fp_line
			(start -0.12065 0.2794)
			(end -0.12065 0.3048)
			(stroke
				(width 0.1)
				(type default)
			)
			(layer "F.Fab")
		)
		(fp_line
			(start -0.12065 -0.2794)
			(end 0.12065 -0.2794)
			(stroke
				(width 0.1)
				(type default)
			)
			(layer "F.Fab")
		)
		(fp_line
			(start -0.12065 -0.305054)
			(end -0.12065 -0.2794)
			(stroke
				(width 0.1)
				(type default)
			)
			(layer "F.Fab")
		)
		(fp_line
			(start -0.67945 0.3048)
			(end -0.67945 -0.305054)
			(stroke
				(width 0.1)
				(type default)
			)
			(layer "F.Fab")
		)
		(fp_line
			(start -0.67945 -0.305054)
			(end -0.12065 -0.305054)
			(stroke
				(width 0.1)
				(type default)
			)
			(layer "F.Fab")
		)
		(pad "1" smd circle
			(at -0.40005 0 180)
			(size 0 0)
			(layers "F.Cu" "F.Mask" "F.Paste")
			(net "P3V3_AUX")
		)
		(pad "2" smd circle
			(at 0.40005 0 180)
			(size 0 0)
			(layers "F.Cu" "F.Mask" "F.Paste")
			(net "PU_CPU0_USB_HUB_RESERVED2")
		)
	)
)
